(kicad_pcb
	(version 20260206)
	(generator "pcbnew")
	(generator_version "10.0")
	(general
		(thickness 1.6)
		(legacy_teardrops no)
	)
	(paper "A4")
	(title_block
		(title "Bryce Canyon_R.DPB_16317-1_OCP.brd")
		(comment 1 "Bryce Canyon / footprints 501-505 of 2099")
	)
	(layers
		(0 "F.Cu" signal "TOP")
		(4 "In1.Cu" signal "L2GND")
		(6 "In2.Cu" signal "L3")
		(8 "In3.Cu" signal "L4VCC")
		(10 "In4.Cu" signal "L5VCC")
		(12 "In5.Cu" signal "L6")
		(14 "In6.Cu" signal "L7GND")
		(2 "B.Cu" signal "BOTTOM")
		(9 "F.Adhes" user "F.Adhesive")
		(11 "B.Adhes" user "B.Adhesive")
		(13 "F.Paste" user "Package Geometry/Pastemask Top")
		(15 "B.Paste" user "Package Geometry/Pastemask Bottom")
		(5 "F.SilkS" user "Ref Des/Silkscreen Top")
		(7 "B.SilkS" user "Ref Des/Silkscreen Bottom")
		(1 "F.Mask" user "Board Geometry/Soldermask Top")
		(3 "B.Mask" user "Board Geometry/Soldermask Bottom")
		(17 "Dwgs.User" user "User.Drawings")
		(19 "Cmts.User" user "User.Comments")
		(21 "Eco1.User" user "User.Eco1")
		(23 "Eco2.User" user "User.Eco2")
		(25 "Edge.Cuts" user "Board Geometry/Outline")
		(27 "Margin" user)
		(31 "F.CrtYd" user "Package Geometry/Place Bound Top")
		(29 "B.CrtYd" user "Package Geometry/Place Bound Bottom")
		(35 "F.Fab" user "Ref Des/Assembly Top")
		(33 "B.Fab" user "Ref Des/Assembly Bottom")
	)
	(footprint ""
		(layer "F.Cu")
		(at 280.4414 -349.3008 90)
		(property "Reference" "R1149"
			(at 0 0 90)
			(layer "F.SilkS")
			(hide yes)
			(effects
				(font
					(size 1.27 1.27)
				)
			)
		)
		(property "Value" "0R2J-2-GP"
			(at 0.064008 -3.993896 90)
			(unlocked yes)
			(layer "F.Fab")
			(hide yes)
			(effects
				(font
					(size 1.016 1.016)
					(thickness 0.1524)
				)
			)
		)
		(property "Device Type" "R402H16"
			(at 0.064008 -5.517896 90)
			(unlocked yes)
			(layer "F.Fab")
			(hide yes)
			(effects
				(font
					(size 1.016 1.016)
					(thickness 0.1524)
				)
			)
		)
		(duplicate_pad_numbers_are_jumpers no)
		(fp_line
			(start 0.508 -0.9398)
			(end -0.508 -0.9398)
			(stroke
				(width 0.1524)
				(type default)
			)
			(layer "F.SilkS")
		)
		(fp_line
			(start -0.508 -0.9398)
			(end -0.508 0.9398)
			(stroke
				(width 0.1524)
				(type default)
			)
			(layer "F.SilkS")
		)
		(fp_rect
			(start -0.508 0.9398)
			(end 0.508 -0.9398)
			(stroke
				(width 0)
				(type default)
			)
			(fill no)
			(layer "F.CrtYd")
		)
		(fp_rect
			(start -0.508 0.9398)
			(end 0.508 -0.9398)
			(stroke
				(width 0)
				(type default)
			)
			(fill no)
			(layer "F.Fab")
		)
		(pad "1" smd custom
			(at 0 -0.4445 90)
			(size 0.1397 0.1397)
			(layers "F.Cu" "F.Mask" "F.Paste")
			(net "P3V3_STBY_B")
			(options
				(clearance outline)
				(anchor circle)
			)
			(primitives
				(gr_poly
					(pts
						(arc
							(start -0.1778 -0.2794)
							(mid -0.249642 -0.249642)
							(end -0.2794 -0.1778)
						)
						(arc
							(start -0.2794 0.1778)
							(mid -0.249642 0.249642)
							(end -0.1778 0.2794)
						)
						(arc
							(start 0.1778 0.2794)
							(mid 0.249642 0.249642)
							(end 0.2794 0.1778)
						)
						(arc
							(start 0.2794 -0.1778)
							(mid 0.249642 -0.249642)
							(end 0.1778 -0.2794)
						)
					)
					(width 0)
					(fill yes)
				)
			)
		)
		(pad "2" smd custom
			(at 0 0.4445 90)
			(size 0.1397 0.1397)
			(layers "F.Cu" "F.Mask" "F.Paste")
			(net "MAX31790_B_PWM_ST1")
			(options
				(clearance outline)
				(anchor circle)
			)
			(primitives
				(gr_poly
					(pts
						(arc
							(start -0.1778 -0.2794)
							(mid -0.249642 -0.249642)
							(end -0.2794 -0.1778)
						)
						(arc
							(start -0.2794 0.1778)
							(mid -0.249642 0.249642)
							(end -0.1778 0.2794)
						)
						(arc
							(start 0.1778 0.2794)
							(mid 0.249642 0.249642)
							(end 0.2794 0.1778)
						)
						(arc
							(start 0.2794 -0.1778)
							(mid 0.249642 -0.249642)
							(end 0.1778 -0.2794)
						)
					)
					(width 0)
					(fill yes)
				)
			)
		)
	)
	(footprint ""
		(layer "F.Cu")
		(at 362.966 -160.02 180)
		(property "Reference" "C282"
			(at 0 0 180)
			(layer "F.SilkS")
			(hide yes)
			(effects
				(font
					(size 1.27 1.27)
				)
			)
		)
		(property "Value" "SC4D7U25V5KX-1-GP"
			(at -0.0762 -6.1214 180)
			(unlocked yes)
			(layer "F.Fab")
			(hide yes)
			(effects
				(font
					(size 1.016 1.016)
					(thickness 0.1524)
				)
			)
		)
		(property "Device Type" "C805H58"
			(at -0.0762 -8.1534 180)
			(unlocked yes)
			(layer "F.Fab")
			(hide yes)
			(effects
				(font
					(size 1.016 1.016)
					(thickness 0.1524)
				)
			)
		)
		(duplicate_pad_numbers_are_jumpers no)
		(fp_line
			(start 0.635 0)
			(end -0.635 0)
			(stroke
				(width 0.508)
				(type default)
			)
			(layer "F.SilkS")
		)
		(fp_rect
			(start -0.9652 1.778)
			(end 0.9652 -1.778)
			(stroke
				(width 0)
				(type default)
			)
			(fill no)
			(layer "F.CrtYd")
		)
		(fp_poly
			(pts
				(xy -0.9652 -1.778) (xy 0.9652 -1.778) (xy 0.9652 1.778) (xy -0.9652 1.778)
			)
			(stroke
				(width 0)
				(type default)
			)
			(fill no)
			(layer "F.Fab")
		)
		(pad "1" smd rect
			(at 0 -0.9652 180)
			(size 1.397 1.143)
			(layers "F.Cu" "F.Mask" "F.Paste")
			(net "P12V_HDD19")
		)
		(pad "2" smd rect
			(at 0 0.9652 180)
			(size 1.397 1.143)
			(layers "F.Cu" "F.Mask" "F.Paste")
			(net "GND")
		)
	)
	(footprint ""
		(layer "F.Cu")
		(at 473.202 -246.888 90)
		(property "Reference" "Q43"
			(at 0 0 90)
			(layer "F.SilkS")
			(hide yes)
			(effects
				(font
					(size 1.27 1.27)
				)
			)
		)
		(property "Value" "2N7002KDW-GP"
			(at -2.3622 -8.2042 90)
			(unlocked yes)
			(layer "F.Fab")
			(hide yes)
			(effects
				(font
					(size 1.016 1.016)
					(thickness 0.1524)
				)
			)
		)
		(property "Device Type" "SOT-363H44"
			(at -2.3622 -10.1092 90)
			(unlocked yes)
			(layer "F.Fab")
			(hide yes)
			(effects
				(font
					(size 1.016 1.016)
					(thickness 0.1524)
				)
			)
		)
		(duplicate_pad_numbers_are_jumpers no)
		(fp_line
			(start 1.4478 -1.7018)
			(end -1.4478 -1.7018)
			(stroke
				(width 0.1524)
				(type default)
			)
			(layer "F.SilkS")
		)
		(fp_line
			(start -1.4478 -1.7018)
			(end -1.4478 1.7018)
			(stroke
				(width 0.1524)
				(type default)
			)
			(layer "F.SilkS")
		)
		(fp_line
			(start -1.27 1.524)
			(end -1.27 0.6604)
			(stroke
				(width 0.4826)
				(type default)
			)
			(layer "F.SilkS")
		)
		(fp_line
			(start 1.4478 1.7018)
			(end 1.4478 -1.7018)
			(stroke
				(width 0.1524)
				(type default)
			)
			(layer "F.SilkS")
		)
		(fp_line
			(start -1.4478 1.7018)
			(end 1.4478 1.7018)
			(stroke
				(width 0.1524)
				(type default)
			)
			(layer "F.SilkS")
		)
		(fp_poly
			(pts
				(xy -1.524 -1.778) (xy 1.524 -1.778) (xy 1.524 1.778) (xy -1.524 1.778)
			)
			(stroke
				(width 0)
				(type default)
			)
			(fill no)
			(layer "F.CrtYd")
		)
		(fp_poly
			(pts
				(xy -1.524 -1.778) (xy 1.524 -1.778) (xy 1.524 1.778) (xy -1.524 1.778)
			)
			(stroke
				(width 0)
				(type default)
			)
			(fill no)
			(layer "F.Fab")
		)
		(pad "1" smd rect
			(at -0.65024 0.9398 90)
			(size 0.4064 1.016)
			(layers "F.Cu" "F.Mask" "F.Paste")
			(net "GND")
		)
		(pad "2" smd rect
			(at 0 0.9398 90)
			(size 0.4064 1.016)
			(layers "F.Cu" "F.Mask" "F.Paste")
			(net "SW_PWR_R_HDD11")
		)
		(pad "3" smd rect
			(at 0.65024 0.9398 90)
			(size 0.4064 1.016)
			(layers "F.Cu" "F.Mask" "F.Paste")
			(net "SW_HDD_P11")
		)
		(pad "4" smd rect
			(at 0.65024 -0.9398 90)
			(size 0.4064 1.016)
			(layers "F.Cu" "F.Mask" "F.Paste")
			(net "GND")
		)
		(pad "5" smd rect
			(at 0 -0.9398 90)
			(size 0.4064 1.016)
			(layers "F.Cu" "F.Mask" "F.Paste")
			(net "SW_HDD_G11")
		)
		(pad "6" smd rect
			(at -0.65024 -0.9398 90)
			(size 0.4064 1.016)
			(layers "F.Cu" "F.Mask" "F.Paste")
			(net "SW_HDD_R11")
		)
	)
	(footprint ""
		(layer "F.Cu")
		(at 50.999898 -379.899926 180)
		(property "Reference" "FAN1"
			(at 0 0 180)
			(layer "F.SilkS")
			(hide yes)
			(effects
				(font
					(size 1.27 1.27)
				)
			)
		)
		(property "Value" "MLX-CONN10D-7-GP"
			(at -15.641574 4.697984 180)
			(unlocked yes)
			(layer "F.Fab")
			(hide yes)
			(effects
				(font
					(size 1.016 1.016)
					(thickness 0.1524)
				)
			)
		)
		(property "Device Type" "15-24-6103"
			(at -15.641574 3.173984 180)
			(unlocked yes)
			(layer "F.Fab")
			(hide yes)
			(effects
				(font
					(size 1.016 1.016)
					(thickness 0.1524)
				)
			)
		)
		(duplicate_pad_numbers_are_jumpers no)
		(fp_line
			(start 14.0462 8.1534)
			(end -14.0462 8.1534)
			(stroke
				(width 0.1524)
				(type default)
			)
			(layer "F.SilkS")
		)
		(fp_line
			(start 14.0462 -6.4516)
			(end 14.0462 8.1534)
			(stroke
				(width 0.1524)
				(type default)
			)
			(layer "F.SilkS")
		)
		(fp_line
			(start 9.9314 -6.4516)
			(end 14.0462 -6.4516)
			(stroke
				(width 0.1524)
				(type default)
			)
			(layer "F.SilkS")
		)
		(fp_line
			(start 9.9314 -14.3256)
			(end 9.9314 -6.4516)
			(stroke
				(width 0.1524)
				(type default)
			)
			(layer "F.SilkS")
		)
		(fp_line
			(start -9.9314 -6.4516)
			(end -9.9314 -14.3256)
			(stroke
				(width 0.1524)
				(type default)
			)
			(layer "F.SilkS")
		)
		(fp_line
			(start -9.9314 -14.3256)
			(end 9.9314 -14.3256)
			(stroke
				(width 0.1524)
				(type default)
			)
			(layer "F.SilkS")
		)
		(fp_line
			(start -14.0462 8.1534)
			(end -14.0462 -6.4516)
			(stroke
				(width 0.1524)
				(type default)
			)
			(layer "F.SilkS")
		)
		(fp_line
			(start -14.0462 -6.4516)
			(end -9.9314 -6.4516)
			(stroke
				(width 0.1524)
				(type default)
			)
			(layer "F.SilkS")
		)
		(fp_circle
			(center 8.400034 -7.29996)
			(end 6.761734 -7.29996)
			(stroke
				(width 0.3048)
				(type default)
			)
			(fill no)
			(layer "F.SilkS")
		)
		(fp_circle
			(center 8.400034 -12.800076)
			(end 6.761734 -12.800076)
			(stroke
				(width 0.3048)
				(type default)
			)
			(fill no)
			(layer "F.SilkS")
		)
		(fp_circle
			(center 4.19989 -7.29996)
			(end 2.56159 -7.29996)
			(stroke
				(width 0.3048)
				(type default)
			)
			(fill no)
			(layer "F.SilkS")
		)
		(fp_circle
			(center 4.19989 -12.800076)
			(end 2.56159 -12.800076)
			(stroke
				(width 0.3048)
				(type default)
			)
			(fill no)
			(layer "F.SilkS")
		)
		(fp_circle
			(center 0 -7.29996)
			(end -1.6383 -7.29996)
			(stroke
				(width 0.3048)
				(type default)
			)
			(fill no)
			(layer "F.SilkS")
		)
		(fp_circle
			(center 0 -12.800076)
			(end -1.6383 -12.800076)
			(stroke
				(width 0.3048)
				(type default)
			)
			(fill no)
			(layer "F.SilkS")
		)
		(fp_circle
			(center -4.19989 -7.29996)
			(end -5.83819 -7.29996)
			(stroke
				(width 0.3048)
				(type default)
			)
			(fill no)
			(layer "F.SilkS")
		)
		(fp_circle
			(center -4.19989 -12.800076)
			(end -5.83819 -12.800076)
			(stroke
				(width 0.3048)
				(type default)
			)
			(fill no)
			(layer "F.SilkS")
		)
		(fp_circle
			(center -8.400034 -7.29996)
			(end -10.038334 -7.29996)
			(stroke
				(width 0.3048)
				(type default)
			)
			(fill no)
			(layer "F.SilkS")
		)
		(fp_circle
			(center -8.400034 -12.800076)
			(end -10.038334 -12.800076)
			(stroke
				(width 0.3048)
				(type default)
			)
			(fill no)
			(layer "F.SilkS")
		)
		(fp_poly
			(pts
				(xy -13.7922 7.8994) (xy -13.7922 -6.1976) (xy -9.2964 -6.1976) (xy -9.2964 -13.6906) (xy 9.2964 -13.6906)
				(xy 9.2964 -6.1976) (xy 13.7922 -6.1976) (xy 13.7922 7.8994)
			)
			(stroke
				(width 0)
				(type default)
			)
			(fill no)
			(layer "F.CrtYd")
		)
		(fp_poly
			(pts
				(xy -14.3002 8.4074) (xy -14.3002 -6.7056) (xy -10.1854 -6.7056) (xy -10.1854 -14.5796) (xy 10.1854 -14.5796)
				(xy 10.1854 -6.7056) (xy 14.3002 -6.7056) (xy 14.3002 -0.00635) (xy 13.7922 -0.00635) (xy 13.7922 -6.1976)
				(xy 9.2964 -6.1976) (xy 9.2964 -13.6906) (xy -9.2964 -13.6906) (xy -9.2964 -6.1976) (xy -13.7922 -6.1976)
				(xy -13.7922 7.8994) (xy 13.7922 7.8994) (xy 13.7922 0.00635) (xy 14.3002 0.00635) (xy 14.3002 8.4074)
			)
			(stroke
				(width 0)
				(type default)
			)
			(fill no)
			(layer "F.CrtYd")
		)
		(fp_poly
			(pts
				(xy -14.3002 8.4074) (xy -14.3002 -6.7056) (xy -10.1854 -6.7056) (xy -10.1854 -14.5796) (xy 10.1854 -14.5796)
				(xy 10.1854 -6.7056) (xy 14.3002 -6.7056) (xy 14.3002 8.4074)
			)
			(stroke
				(width 0)
				(type default)
			)
			(fill no)
			(layer "F.Fab")
		)
		(pad "" np_thru_hole circle
			(at -8.400034 0 180)
			(size 0.254 0.254)
			(drill 3.0226)
			(layers "*.Cu" "*.Mask")
			(clearance 1.7399)
			(thermal_gap 1.7399)
		)
		(pad "" np_thru_hole circle
			(at 8.400034 0 180)
			(size 0.254 0.254)
			(drill 3.0226)
			(layers "*.Cu" "*.Mask")
			(clearance 1.7399)
			(thermal_gap 1.7399)
		)
		(pad "1" thru_hole circle
			(at 8.400034 -7.29996 180)
			(size 2.5654 2.5654)
			(drill 1.8034)
			(layers "*.Cu" "*.Mask")
			(remove_unused_layers no)
			(net "FAN_0_TACH0")
			(clearance 0.127)
			(thermal_gap 0.127)
		)
		(pad "2" thru_hole circle
			(at 8.400034 -12.800076 180)
			(size 2.5654 2.5654)
			(drill 1.8034)
			(layers "*.Cu" "*.Mask")
			(remove_unused_layers no)
			(net "FAN_0_TACH1")
			(clearance 0.127)
			(thermal_gap 0.127)
		)
		(pad "3" thru_hole circle
			(at 4.19989 -7.29996 180)
			(size 2.5654 2.5654)
			(drill 1.8034)
			(layers "*.Cu" "*.Mask")
			(remove_unused_layers no)
			(net "FAN_0_PWM")
			(clearance 0.127)
			(thermal_gap 0.127)
		)
		(pad "4" thru_hole circle
			(at 4.19989 -12.800076 180)
			(size 2.5654 2.5654)
			(drill 1.8034)
			(layers "*.Cu" "*.Mask")
			(remove_unused_layers no)
			(net "FAN_0_PWM")
			(clearance 0.127)
			(thermal_gap 0.127)
		)
		(pad "5" thru_hole circle
			(at 0 -7.29996 180)
			(size 2.5654 2.5654)
			(drill 1.8034)
			(layers "*.Cu" "*.Mask")
			(remove_unused_layers no)
			(net "FAN_0_INS_N")
			(clearance 0.127)
			(thermal_gap 0.127)
		)
		(pad "6" thru_hole circle
			(at 0 -12.800076 180)
			(size 2.5654 2.5654)
			(drill 1.8034)
			(layers "*.Cu" "*.Mask")
			(remove_unused_layers no)
			(net "Net_1778")
			(clearance 0.127)
			(thermal_gap 0.127)
		)
		(pad "7" thru_hole circle
			(at -4.19989 -7.29996 180)
			(size 2.5654 2.5654)
			(drill 1.8034)
			(layers "*.Cu" "*.Mask")
			(remove_unused_layers no)
			(net "P12V_FAN0")
			(clearance 0.127)
			(thermal_gap 0.127)
		)
		(pad "8" thru_hole circle
			(at -4.19989 -12.800076 180)
			(size 2.5654 2.5654)
			(drill 1.8034)
			(layers "*.Cu" "*.Mask")
			(remove_unused_layers no)
			(net "P12V_FAN0")
			(clearance 0.127)
			(thermal_gap 0.127)
		)
		(pad "9" thru_hole circle
			(at -8.400034 -7.29996 180)
			(size 2.5654 2.5654)
			(drill 1.8034)
			(layers "*.Cu" "*.Mask")
			(remove_unused_layers no)
			(net "GND")
			(clearance 0.127)
			(thermal_gap 0.127)
		)
		(pad "10" thru_hole circle
			(at -8.400034 -12.800076 180)
			(size 2.5654 2.5654)
			(drill 1.8034)
			(layers "*.Cu" "*.Mask")
			(remove_unused_layers no)
			(net "GND")
			(clearance 0.127)
			(thermal_gap 0.127)
		)
		(zone
			(layers "F.Cu" "B.Cu" "In1.Cu" "In2.Cu" "In3.Cu" "In4.Cu" "In5.Cu" "In6.Cu")
			(hatch none 0.5)
			(connect_pads
				(clearance 0)
			)
			(min_thickness 0.25)
			(keepout
				(tracks not_allowed)
				(vias allowed)
				(pads allowed)
				(copperpour not_allowed)
				(footprints allowed)
			)
			(placement
				(enabled no)
				(sheetname "")
			)
			(fill
				(thermal_gap 0.5)
				(thermal_bridge_width 0.5)
				(island_removal_mode 0)
			)
			(polygon
				(pts
					(arc
						(start 44.415964 -379.899926)
						(mid 40.783764 -379.899926)
						(end 44.415964 -379.899926)
					)
				)
			)
		)
		(zone
			(layers "F.Cu" "B.Cu" "In1.Cu" "In2.Cu" "In3.Cu" "In4.Cu" "In5.Cu" "In6.Cu")
			(hatch none 0.5)
			(connect_pads
				(clearance 0)
			)
			(min_thickness 0.25)
			(keepout
				(tracks not_allowed)
				(vias allowed)
				(pads allowed)
				(copperpour not_allowed)
				(footprints allowed)
			)
			(placement
				(enabled no)
				(sheetname "")
			)
			(fill
				(thermal_gap 0.5)
				(thermal_bridge_width 0.5)
				(island_removal_mode 0)
			)
			(polygon
				(pts
					(arc
						(start 61.216032 -379.899926)
						(mid 57.583832 -379.899926)
						(end 61.216032 -379.899926)
					)
				)
			)
		)
	)
	(footprint ""
		(layer "F.Cu")
		(at 55.0164 -14.5796 90)
		(property "Reference" "R662"
			(at 0 0 90)
			(layer "F.SilkS")
			(hide yes)
			(effects
				(font
					(size 1.27 1.27)
				)
			)
		)
		(property "Value" "0R2J-2-GP"
			(at 0.064008 -3.993896 90)
			(unlocked yes)
			(layer "F.Fab")
			(hide yes)
			(effects
				(font
					(size 1.016 1.016)
					(thickness 0.1524)
				)
			)
		)
		(property "Device Type" "R402H16"
			(at 0.064008 -5.517896 90)
			(unlocked yes)
			(layer "F.Fab")
			(hide yes)
			(effects
				(font
					(size 1.016 1.016)
					(thickness 0.1524)
				)
			)
		)
		(duplicate_pad_numbers_are_jumpers no)
		(fp_line
			(start 0.508 -0.9398)
			(end -0.508 -0.9398)
			(stroke
				(width 0.1524)
				(type default)
			)
			(layer "F.SilkS")
		)
		(fp_line
			(start -0.508 -0.9398)
			(end -0.508 0.9398)
			(stroke
				(width 0.1524)
				(type default)
			)
			(layer "F.SilkS")
		)
		(fp_rect
			(start -0.508 0.9398)
			(end 0.508 -0.9398)
			(stroke
				(width 0)
				(type default)
			)
			(fill no)
			(layer "F.CrtYd")
		)
		(fp_rect
			(start -0.508 0.9398)
			(end 0.508 -0.9398)
			(stroke
				(width 0)
				(type default)
			)
			(fill no)
			(layer "F.Fab")
		)
		(pad "1" smd custom
			(at 0 -0.4445 90)
			(size 0.1397 0.1397)
			(layers "F.Cu" "F.Mask" "F.Paste")
			(net "SW_HDD_G25")
			(options
				(clearance outline)
				(anchor circle)
			)
			(primitives
				(gr_poly
					(pts
						(arc
							(start -0.1778 -0.2794)
							(mid -0.249642 -0.249642)
							(end -0.2794 -0.1778)
						)
						(arc
							(start -0.2794 0.1778)
							(mid -0.249642 0.249642)
							(end -0.1778 0.2794)
						)
						(arc
							(start 0.1778 0.2794)
							(mid 0.249642 0.249642)
							(end 0.2794 0.1778)
						)
						(arc
							(start 0.2794 -0.1778)
							(mid 0.249642 -0.249642)
							(end 0.1778 -0.2794)
						)
					)
					(width 0)
					(fill yes)
				)
			)
		)
		(pad "2" smd custom
			(at 0 0.4445 90)
			(size 0.1397 0.1397)
			(layers "F.Cu" "F.Mask" "F.Paste")
			(net "SW_HDD_R25")
			(options
				(clearance outline)
				(anchor circle)
			)
			(primitives
				(gr_poly
					(pts
						(arc
							(start -0.1778 -0.2794)
							(mid -0.249642 -0.249642)
							(end -0.2794 -0.1778)
						)
						(arc
							(start -0.2794 0.1778)
							(mid -0.249642 0.249642)
							(end -0.1778 0.2794)
						)
						(arc
							(start 0.1778 0.2794)
							(mid 0.249642 0.249642)
							(end 0.2794 0.1778)
						)
						(arc
							(start 0.2794 -0.1778)
							(mid 0.249642 -0.249642)
							(end 0.1778 -0.2794)
						)
					)
					(width 0)
					(fill yes)
				)
			)
		)
	)
)
